# S9S_MB_2U (Grand Teton) — schematic netlist excerpt (pin names and nets, part order shuffled) for the footprints in the layout excerpt that follows; sources: Cadence DE-HDL packaged netlist, KiCad conversion of 03242023_DA0F0TMBIJ0_F0T_Motherboard_J_brd_V01_OCP.brd

R1206  Q_RES  33.2 1% CHIP  pkg 0402LF  page 223 : A = RST_MB_STBY_R_N ; B = RST_MB_STBY_N
R665  Q_RES  0 5% EMPTY  pkg 0402LF  page 230 : A = I3C_SPD_DDRABCD_CPU1_R_SCL ; B = I3C_SPD_DDRABCD_CPU1_LVC1_R_SCL

(kicad_pcb
	(version 20260206)
	(generator "pcbnew")
	(generator_version "10.0")
	(general
		(thickness 1.6)
		(legacy_teardrops no)
	)
	(paper "A4")
	(title_block
		(title "03242023_DA0F0TMBIJ0_F0T_Motherboard_J_brd_V01_OCP.brd")
		(comment 1 "Grand Teton / footprints 1530-1531 of 6105")
	)
	(layers
		(0 "F.Cu" signal "TOP")
		(4 "In1.Cu" signal "GND")
		(6 "In2.Cu" signal "IN1")
		(8 "In3.Cu" signal "GND1")
		(10 "In4.Cu" signal "IN2")
		(12 "In5.Cu" signal "GND2")
		(14 "In6.Cu" signal "IN3")
		(16 "In7.Cu" signal "GND3")
		(18 "In8.Cu" signal "VCC")
		(20 "In9.Cu" signal "VCC1")
		(22 "In10.Cu" signal "GND4")
		(24 "In11.Cu" signal "IN4")
		(26 "In12.Cu" signal "GND5")
		(28 "In13.Cu" signal "IN5")
		(30 "In14.Cu" signal "GND6")
		(32 "In15.Cu" signal "IN6")
		(34 "In16.Cu" signal "GND7")
		(2 "B.Cu" signal "BOTTOM")
		(9 "F.Adhes" user "F.Adhesive")
		(11 "B.Adhes" user "B.Adhesive")
		(13 "F.Paste" user "Package Geometry/Pastemask Top")
		(15 "B.Paste" user "Package Geometry/Pastemask Bottom")
		(5 "F.SilkS" user "Ref Des/Silkscreen Top")
		(7 "B.SilkS" user "Ref Des/Silkscreen Bottom")
		(1 "F.Mask" user "Board Geometry/Soldermask Top")
		(3 "B.Mask" user "Board Geometry/Soldermask Bottom")
		(17 "Dwgs.User" user "User.Drawings")
		(19 "Cmts.User" user "User.Comments")
		(21 "Eco1.User" user "User.Eco1")
		(23 "Eco2.User" user "User.Eco2")
		(25 "Edge.Cuts" user "Board Geometry/Outline")
		(27 "Margin" user)
		(31 "F.CrtYd" user "Package Geometry/Place Bound Top")
		(29 "B.CrtYd" user "Package Geometry/Place Bound Bottom")
		(35 "F.Fab" user "Ref Des/Assembly Top")
		(33 "B.Fab" user "Ref Des/Assembly Bottom")
	)
	(footprint ""
		(layer "F.Cu")
		(at 78.160626 -151.210772)
		(property "Reference" "R665"
			(at 0 0 0)
			(layer "F.SilkS")
			(hide yes)
			(effects
				(font
					(size 1.27 1.27)
				)
			)
		)
		(property "Value" ""
			(at 0 0 0)
			(layer "F.Fab")
			(effects
				(font
					(size 1.27 1.27)
				)
			)
		)
		(duplicate_pad_numbers_are_jumpers no)
		(fp_line
			(start -0.7874 -0.4064)
			(end 0.7874 -0.4064)
			(stroke
				(width 0.1524)
				(type default)
			)
			(layer "F.SilkS")
		)
		(fp_line
			(start -0.7874 0.4064)
			(end -0.7874 -0.4064)
			(stroke
				(width 0.1524)
				(type default)
			)
			(layer "F.SilkS")
		)
		(fp_line
			(start 0.7874 -0.4064)
			(end 0.7874 0.4064)
			(stroke
				(width 0.1524)
				(type default)
			)
			(layer "F.SilkS")
		)
		(fp_line
			(start 0.7874 0.4064)
			(end -0.7874 0.4064)
			(stroke
				(width 0.1524)
				(type default)
			)
			(layer "F.SilkS")
		)
		(fp_line
			(start -0.67945 -0.305054)
			(end -0.12065 -0.305054)
			(stroke
				(width 0.1)
				(type default)
			)
			(layer "F.Fab")
		)
		(fp_line
			(start -0.67945 0.3048)
			(end -0.67945 -0.305054)
			(stroke
				(width 0.1)
				(type default)
			)
			(layer "F.Fab")
		)
		(fp_line
			(start -0.12065 -0.305054)
			(end -0.12065 -0.2794)
			(stroke
				(width 0.1)
				(type default)
			)
			(layer "F.Fab")
		)
		(fp_line
			(start -0.12065 -0.2794)
			(end 0.12065 -0.2794)
			(stroke
				(width 0.1)
				(type default)
			)
			(layer "F.Fab")
		)
		(fp_line
			(start -0.12065 0.2794)
			(end -0.12065 0.3048)
			(stroke
				(width 0.1)
				(type default)
			)
			(layer "F.Fab")
		)
		(fp_line
			(start -0.12065 0.3048)
			(end -0.67945 0.3048)
			(stroke
				(width 0.1)
				(type default)
			)
			(layer "F.Fab")
		)
		(fp_line
			(start 0.120396 0.2794)
			(end -0.12065 0.2794)
			(stroke
				(width 0.1)
				(type default)
			)
			(layer "F.Fab")
		)
		(fp_line
			(start 0.120396 0.3048)
			(end 0.120396 0.2794)
			(stroke
				(width 0.1)
				(type default)
			)
			(layer "F.Fab")
		)
		(fp_line
			(start 0.12065 -0.3048)
			(end 0.67945 -0.3048)
			(stroke
				(width 0.1)
				(type default)
			)
			(layer "F.Fab")
		)
		(fp_line
			(start 0.12065 -0.2794)
			(end 0.12065 -0.3048)
			(stroke
				(width 0.1)
				(type default)
			)
			(layer "F.Fab")
		)
		(fp_line
			(start 0.67945 -0.3048)
			(end 0.67945 0.3048)
			(stroke
				(width 0.1)
				(type default)
			)
			(layer "F.Fab")
		)
		(fp_line
			(start 0.67945 0.3048)
			(end 0.120396 0.3048)
			(stroke
				(width 0.1)
				(type default)
			)
			(layer "F.Fab")
		)
		(pad "1" smd circle
			(at -0.40005 0)
			(size 0 0)
			(layers "F.Cu" "F.Mask" "F.Paste")
			(net "I3C_SPD_DDRABCD_CPU1_R_SCL")
		)
		(pad "2" smd circle
			(at 0.40005 0)
			(size 0 0)
			(layers "F.Cu" "F.Mask" "F.Paste")
			(net "I3C_SPD_DDRABCD_CPU1_LVC1_R_SCL")
		)
	)
	(footprint ""
		(layer "F.Cu")
		(at 197.41388 -104.955848)
		(property "Reference" "R1206"
			(at 0 0 0)
			(layer "F.SilkS")
			(hide yes)
			(effects
				(font
					(size 1.27 1.27)
				)
			)
		)
		(property "Value" ""
			(at 0 0 0)
			(layer "F.Fab")
			(effects
				(font
					(size 1.27 1.27)
				)
			)
		)
		(duplicate_pad_numbers_are_jumpers no)
		(fp_line
			(start -0.7874 -0.4064)
			(end 0.7874 -0.4064)
			(stroke
				(width 0.1524)
				(type default)
			)
			(layer "F.SilkS")
		)
		(fp_line
			(start -0.7874 0.4064)
			(end -0.7874 -0.4064)
			(stroke
				(width 0.1524)
				(type default)
			)
			(layer "F.SilkS")
		)
		(fp_line
			(start 0.7874 -0.4064)
			(end 0.7874 0.4064)
			(stroke
				(width 0.1524)
				(type default)
			)
			(layer "F.SilkS")
		)
		(fp_line
			(start 0.7874 0.4064)
			(end -0.7874 0.4064)
			(stroke
				(width 0.1524)
				(type default)
			)
			(layer "F.SilkS")
		)
		(fp_line
			(start -0.67945 -0.305054)
			(end -0.12065 -0.305054)
			(stroke
				(width 0.1)
				(type default)
			)
			(layer "F.Fab")
		)
		(fp_line
			(start -0.67945 0.3048)
			(end -0.67945 -0.305054)
			(stroke
				(width 0.1)
				(type default)
			)
			(layer "F.Fab")
		)
		(fp_line
			(start -0.12065 -0.305054)
			(end -0.12065 -0.2794)
			(stroke
				(width 0.1)
				(type default)
			)
			(layer "F.Fab")
		)
		(fp_line
			(start -0.12065 -0.2794)
			(end 0.12065 -0.2794)
			(stroke
				(width 0.1)
				(type default)
			)
			(layer "F.Fab")
		)
		(fp_line
			(start -0.12065 0.2794)
			(end -0.12065 0.3048)
			(stroke
				(width 0.1)
				(type default)
			)
			(layer "F.Fab")
		)
		(fp_line
			(start -0.12065 0.3048)
			(end -0.67945 0.3048)
			(stroke
				(width 0.1)
				(type default)
			)
			(layer "F.Fab")
		)
		(fp_line
			(start 0.120396 0.2794)
			(end -0.12065 0.2794)
			(stroke
				(width 0.1)
				(type default)
			)
			(layer "F.Fab")
		)
		(fp_line
			(start 0.120396 0.3048)
			(end 0.120396 0.2794)
			(stroke
				(width 0.1)
				(type default)
			)
			(layer "F.Fab")
		)
		(fp_line
			(start 0.12065 -0.3048)
			(end 0.67945 -0.3048)
			(stroke
				(width 0.1)
				(type default)
			)
			(layer "F.Fab")
		)
		(fp_line
			(start 0.12065 -0.2794)
			(end 0.12065 -0.3048)
			(stroke
				(width 0.1)
				(type default)
			)
			(layer "F.Fab")
		)
		(fp_line
			(start 0.67945 -0.3048)
			(end 0.67945 0.3048)
			(stroke
				(width 0.1)
				(type default)
			)
			(layer "F.Fab")
		)
		(fp_line
			(start 0.67945 0.3048)
			(end 0.120396 0.3048)
			(stroke
				(width 0.1)
				(type default)
			)
			(layer "F.Fab")
		)
		(pad "1" smd circle
			(at -0.40005 0)
			(size 0 0)
			(layers "F.Cu" "F.Mask" "F.Paste")
			(net "RST_MB_STBY_R_N")
		)
		(pad "2" smd circle
			(at 0.40005 0)
			(size 0 0)
			(layers "F.Cu" "F.Mask" "F.Paste")
			(net "RST_MB_STBY_N")
		)
	)
)
